# T6G (Grand Teton) — schematic netlist excerpt (pin names and nets, part order shuffled) for the footprints in the layout excerpt that follows; sources: Cadence DE-HDL packaged netlist, KiCad conversion of 04192023_DAF0TMB3IC0_F0TG_MB_C_brd_V02_OCP.brd

R6257  Q_RES  1M 1% CHIP  pkg 0402LF  page 179 : A = XTAL_USB_CPU0_HUB2_XOUT ; B = XTAL_USB_CPU0_HUB2_XIN
PR207  Q_RES  8.87K 1% EMPTY  pkg 0402LF  page 215 : A = GND ; B = PVDDCR_SOC_P1_LSET1

(kicad_pcb
	(version 20260206)
	(generator "pcbnew")
	(generator_version "10.0")
	(general
		(thickness 1.6)
		(legacy_teardrops no)
	)
	(paper "A4")
	(title_block
		(title "04192023_DAF0TMB3IC0_F0TG_MB_C_brd_V02_OCP.brd")
		(comment 1 "Grand Teton / footprints 2569-2570 of 8354")
	)
	(layers
		(0 "F.Cu" signal "TOP")
		(4 "In1.Cu" signal "GND")
		(6 "In2.Cu" signal "IN1")
		(8 "In3.Cu" signal "GND1")
		(10 "In4.Cu" signal "IN2")
		(12 "In5.Cu" signal "GND2")
		(14 "In6.Cu" signal "IN3")
		(16 "In7.Cu" signal "GND3")
		(18 "In8.Cu" signal "VCC")
		(20 "In9.Cu" signal "VCC1")
		(22 "In10.Cu" signal "GND4")
		(24 "In11.Cu" signal "IN4")
		(26 "In12.Cu" signal "GND5")
		(28 "In13.Cu" signal "IN5")
		(30 "In14.Cu" signal "GND6")
		(32 "In15.Cu" signal "IN6")
		(34 "In16.Cu" signal "GND7")
		(2 "B.Cu" signal "BOTTOM")
		(9 "F.Adhes" user "F.Adhesive")
		(11 "B.Adhes" user "B.Adhesive")
		(13 "F.Paste" user "Package Geometry/Pastemask Top")
		(15 "B.Paste" user "Package Geometry/Pastemask Bottom")
		(5 "F.SilkS" user "Ref Des/Silkscreen Top")
		(7 "B.SilkS" user "Ref Des/Silkscreen Bottom")
		(1 "F.Mask" user "Board Geometry/Soldermask Top")
		(3 "B.Mask" user "Board Geometry/Soldermask Bottom")
		(17 "Dwgs.User" user "User.Drawings")
		(19 "Cmts.User" user "User.Comments")
		(21 "Eco1.User" user "User.Eco1")
		(23 "Eco2.User" user "User.Eco2")
		(25 "Edge.Cuts" user "Board Geometry/Outline")
		(27 "Margin" user)
		(31 "F.CrtYd" user "Package Geometry/Place Bound Top")
		(29 "B.CrtYd" user "Package Geometry/Place Bound Bottom")
		(35 "F.Fab" user "Ref Des/Assembly Top")
		(33 "B.Fab" user "Ref Des/Assembly Bottom")
	)
	(footprint ""
		(layer "F.Cu")
		(at 116.990114 -166.711884)
		(property "Reference" "PR207"
			(at 0 0 0)
			(layer "F.SilkS")
			(hide yes)
			(effects
				(font
					(size 1.27 1.27)
				)
			)
		)
		(property "Value" ""
			(at 0 0 0)
			(layer "F.Fab")
			(effects
				(font
					(size 1.27 1.27)
				)
			)
		)
		(duplicate_pad_numbers_are_jumpers no)
		(fp_line
			(start -0.7874 -0.4064)
			(end 0.7874 -0.4064)
			(stroke
				(width 0.1524)
				(type default)
			)
			(layer "F.SilkS")
		)
		(fp_line
			(start -0.7874 0.4064)
			(end -0.7874 -0.4064)
			(stroke
				(width 0.1524)
				(type default)
			)
			(layer "F.SilkS")
		)
		(fp_line
			(start 0.7874 -0.4064)
			(end 0.7874 0.4064)
			(stroke
				(width 0.1524)
				(type default)
			)
			(layer "F.SilkS")
		)
		(fp_line
			(start 0.7874 0.4064)
			(end -0.7874 0.4064)
			(stroke
				(width 0.1524)
				(type default)
			)
			(layer "F.SilkS")
		)
		(fp_line
			(start -0.67945 -0.305054)
			(end -0.12065 -0.305054)
			(stroke
				(width 0.1)
				(type default)
			)
			(layer "F.Fab")
		)
		(fp_line
			(start -0.67945 0.3048)
			(end -0.67945 -0.305054)
			(stroke
				(width 0.1)
				(type default)
			)
			(layer "F.Fab")
		)
		(fp_line
			(start -0.12065 -0.305054)
			(end -0.12065 -0.2794)
			(stroke
				(width 0.1)
				(type default)
			)
			(layer "F.Fab")
		)
		(fp_line
			(start -0.12065 -0.2794)
			(end 0.12065 -0.2794)
			(stroke
				(width 0.1)
				(type default)
			)
			(layer "F.Fab")
		)
		(fp_line
			(start -0.12065 0.2794)
			(end -0.12065 0.3048)
			(stroke
				(width 0.1)
				(type default)
			)
			(layer "F.Fab")
		)
		(fp_line
			(start -0.12065 0.3048)
			(end -0.67945 0.3048)
			(stroke
				(width 0.1)
				(type default)
			)
			(layer "F.Fab")
		)
		(fp_line
			(start 0.120396 0.2794)
			(end -0.12065 0.2794)
			(stroke
				(width 0.1)
				(type default)
			)
			(layer "F.Fab")
		)
		(fp_line
			(start 0.120396 0.3048)
			(end 0.120396 0.2794)
			(stroke
				(width 0.1)
				(type default)
			)
			(layer "F.Fab")
		)
		(fp_line
			(start 0.12065 -0.3048)
			(end 0.67945 -0.3048)
			(stroke
				(width 0.1)
				(type default)
			)
			(layer "F.Fab")
		)
		(fp_line
			(start 0.12065 -0.2794)
			(end 0.12065 -0.3048)
			(stroke
				(width 0.1)
				(type default)
			)
			(layer "F.Fab")
		)
		(fp_line
			(start 0.67945 -0.3048)
			(end 0.67945 0.3048)
			(stroke
				(width 0.1)
				(type default)
			)
			(layer "F.Fab")
		)
		(fp_line
			(start 0.67945 0.3048)
			(end 0.120396 0.3048)
			(stroke
				(width 0.1)
				(type default)
			)
			(layer "F.Fab")
		)
		(pad "1" smd circle
			(at -0.40005 0)
			(size 0 0)
			(layers "F.Cu" "F.Mask" "F.Paste")
			(net "GND")
		)
		(pad "2" smd circle
			(at 0.40005 0)
			(size 0 0)
			(layers "F.Cu" "F.Mask" "F.Paste")
			(net "PVDDCR_SOC_P1_LSET1")
		)
	)
	(footprint ""
		(layer "F.Cu")
		(at 106.235754 -26.453592)
		(property "Reference" "R6257"
			(at 0 0 0)
			(layer "F.SilkS")
			(hide yes)
			(effects
				(font
					(size 1.27 1.27)
				)
			)
		)
		(property "Value" ""
			(at 0 0 0)
			(layer "F.Fab")
			(effects
				(font
					(size 1.27 1.27)
				)
			)
		)
		(duplicate_pad_numbers_are_jumpers no)
		(fp_line
			(start -0.7874 -0.4064)
			(end 0.7874 -0.4064)
			(stroke
				(width 0.1524)
				(type default)
			)
			(layer "F.SilkS")
		)
		(fp_line
			(start -0.7874 0.4064)
			(end -0.7874 -0.4064)
			(stroke
				(width 0.1524)
				(type default)
			)
			(layer "F.SilkS")
		)
		(fp_line
			(start 0.7874 -0.4064)
			(end 0.7874 0.4064)
			(stroke
				(width 0.1524)
				(type default)
			)
			(layer "F.SilkS")
		)
		(fp_line
			(start 0.7874 0.4064)
			(end -0.7874 0.4064)
			(stroke
				(width 0.1524)
				(type default)
			)
			(layer "F.SilkS")
		)
		(fp_line
			(start -0.67945 -0.305054)
			(end -0.12065 -0.305054)
			(stroke
				(width 0.1)
				(type default)
			)
			(layer "F.Fab")
		)
		(fp_line
			(start -0.67945 0.3048)
			(end -0.67945 -0.305054)
			(stroke
				(width 0.1)
				(type default)
			)
			(layer "F.Fab")
		)
		(fp_line
			(start -0.12065 -0.305054)
			(end -0.12065 -0.2794)
			(stroke
				(width 0.1)
				(type default)
			)
			(layer "F.Fab")
		)
		(fp_line
			(start -0.12065 -0.2794)
			(end 0.12065 -0.2794)
			(stroke
				(width 0.1)
				(type default)
			)
			(layer "F.Fab")
		)
		(fp_line
			(start -0.12065 0.2794)
			(end -0.12065 0.3048)
			(stroke
				(width 0.1)
				(type default)
			)
			(layer "F.Fab")
		)
		(fp_line
			(start -0.12065 0.3048)
			(end -0.67945 0.3048)
			(stroke
				(width 0.1)
				(type default)
			)
			(layer "F.Fab")
		)
		(fp_line
			(start 0.120396 0.2794)
			(end -0.12065 0.2794)
			(stroke
				(width 0.1)
				(type default)
			)
			(layer "F.Fab")
		)
		(fp_line
			(start 0.120396 0.3048)
			(end 0.120396 0.2794)
			(stroke
				(width 0.1)
				(type default)
			)
			(layer "F.Fab")
		)
		(fp_line
			(start 0.12065 -0.3048)
			(end 0.67945 -0.3048)
			(stroke
				(width 0.1)
				(type default)
			)
			(layer "F.Fab")
		)
		(fp_line
			(start 0.12065 -0.2794)
			(end 0.12065 -0.3048)
			(stroke
				(width 0.1)
				(type default)
			)
			(layer "F.Fab")
		)
		(fp_line
			(start 0.67945 -0.3048)
			(end 0.67945 0.3048)
			(stroke
				(width 0.1)
				(type default)
			)
			(layer "F.Fab")
		)
		(fp_line
			(start 0.67945 0.3048)
			(end 0.120396 0.3048)
			(stroke
				(width 0.1)
				(type default)
			)
			(layer "F.Fab")
		)
		(pad "1" smd circle
			(at -0.40005 0)
			(size 0 0)
			(layers "F.Cu" "F.Mask" "F.Paste")
			(net "XTAL_USB_CPU0_HUB2_XOUT")
		)
		(pad "2" smd circle
			(at 0.40005 0)
			(size 0 0)
			(layers "F.Cu" "F.Mask" "F.Paste")
			(net "XTAL_USB_CPU0_HUB2_XIN")
		)
	)
)
